# T6G (Grand Teton) — schematic netlist excerpt (pin names and nets, part order shuffled) for the footprints in the layout excerpt that follows; sources: Cadence DE-HDL packaged netlist, KiCad conversion of 04192023_DAF0TMB3IC0_F0TG_MB_C_brd_V02_OCP.brd

C2620  Q_CAP  22UF 4V 20% X6S  pkg C0402  page 70 : A = PVDDIO_P0 ; B = GND
R1152  Q_RES  0 5% EMPTY  pkg 0402LF  page 160 : A = SMB_CPU0_CPU1_APML_BUF1_SDA_R1 ; B = SMB_CPU0_CPU1_APML_BUF1_SDA_R2

(kicad_pcb
	(version 20260206)
	(generator "pcbnew")
	(generator_version "10.0")
	(general
		(thickness 1.6)
		(legacy_teardrops no)
	)
	(paper "A4")
	(title_block
		(title "04192023_DAF0TMB3IC0_F0TG_MB_C_brd_V02_OCP.brd")
		(comment 1 "Grand Teton / footprints 6856-6857 of 8354")
	)
	(layers
		(0 "F.Cu" signal "TOP")
		(4 "In1.Cu" signal "GND")
		(6 "In2.Cu" signal "IN1")
		(8 "In3.Cu" signal "GND1")
		(10 "In4.Cu" signal "IN2")
		(12 "In5.Cu" signal "GND2")
		(14 "In6.Cu" signal "IN3")
		(16 "In7.Cu" signal "GND3")
		(18 "In8.Cu" signal "VCC")
		(20 "In9.Cu" signal "VCC1")
		(22 "In10.Cu" signal "GND4")
		(24 "In11.Cu" signal "IN4")
		(26 "In12.Cu" signal "GND5")
		(28 "In13.Cu" signal "IN5")
		(30 "In14.Cu" signal "GND6")
		(32 "In15.Cu" signal "IN6")
		(34 "In16.Cu" signal "GND7")
		(2 "B.Cu" signal "BOTTOM")
		(9 "F.Adhes" user "F.Adhesive")
		(11 "B.Adhes" user "B.Adhesive")
		(13 "F.Paste" user "Package Geometry/Pastemask Top")
		(15 "B.Paste" user "Package Geometry/Pastemask Bottom")
		(5 "F.SilkS" user "Ref Des/Silkscreen Top")
		(7 "B.SilkS" user "Ref Des/Silkscreen Bottom")
		(1 "F.Mask" user "Board Geometry/Soldermask Top")
		(3 "B.Mask" user "Board Geometry/Soldermask Bottom")
		(17 "Dwgs.User" user "User.Drawings")
		(19 "Cmts.User" user "User.Comments")
		(21 "Eco1.User" user "User.Eco1")
		(23 "Eco2.User" user "User.Eco2")
		(25 "Edge.Cuts" user "Board Geometry/Outline")
		(27 "Margin" user)
		(31 "F.CrtYd" user "Package Geometry/Place Bound Top")
		(29 "B.CrtYd" user "Package Geometry/Place Bound Bottom")
		(35 "F.Fab" user "Ref Des/Assembly Top")
		(33 "B.Fab" user "Ref Des/Assembly Bottom")
	)
	(footprint ""
		(layer "B.Cu")
		(at 353.900232 -259.355082 180)
		(property "Reference" "C2620"
			(at 0 0 0)
			(layer "B.SilkS")
			(hide yes)
			(effects
				(font
					(size 1.27 1.27)
				)
				(justify mirror)
			)
		)
		(property "Value" ""
			(at 0 0 0)
			(layer "B.Fab")
			(effects
				(font
					(size 1.27 1.27)
				)
				(justify mirror)
			)
		)
		(duplicate_pad_numbers_are_jumpers no)
		(fp_line
			(start 0.7874 0.4064)
			(end 0.7874 -0.4064)
			(stroke
				(width 0.1524)
				(type default)
			)
			(layer "B.SilkS")
		)
		(fp_line
			(start 0.7874 -0.4064)
			(end -0.7874 -0.4064)
			(stroke
				(width 0.1524)
				(type default)
			)
			(layer "B.SilkS")
		)
		(fp_line
			(start -0.7874 0.4064)
			(end 0.7874 0.4064)
			(stroke
				(width 0.1524)
				(type default)
			)
			(layer "B.SilkS")
		)
		(fp_line
			(start -0.7874 -0.4064)
			(end -0.7874 0.4064)
			(stroke
				(width 0.1524)
				(type default)
			)
			(layer "B.SilkS")
		)
		(fp_line
			(start 0.67945 0.3048)
			(end 0.67945 -0.305054)
			(stroke
				(width 0.1)
				(type default)
			)
			(layer "B.Fab")
		)
		(fp_line
			(start 0.67945 -0.305054)
			(end 0.12065 -0.305054)
			(stroke
				(width 0.1)
				(type default)
			)
			(layer "B.Fab")
		)
		(fp_line
			(start 0.12065 0.3048)
			(end 0.67945 0.3048)
			(stroke
				(width 0.1)
				(type default)
			)
			(layer "B.Fab")
		)
		(fp_line
			(start 0.12065 0.2794)
			(end 0.12065 0.3048)
			(stroke
				(width 0.1)
				(type default)
			)
			(layer "B.Fab")
		)
		(fp_line
			(start 0.12065 -0.2794)
			(end -0.12065 -0.2794)
			(stroke
				(width 0.1)
				(type default)
			)
			(layer "B.Fab")
		)
		(fp_line
			(start 0.12065 -0.305054)
			(end 0.12065 -0.2794)
			(stroke
				(width 0.1)
				(type default)
			)
			(layer "B.Fab")
		)
		(fp_line
			(start -0.120396 0.3048)
			(end -0.120396 0.2794)
			(stroke
				(width 0.1)
				(type default)
			)
			(layer "B.Fab")
		)
		(fp_line
			(start -0.120396 0.2794)
			(end 0.12065 0.2794)
			(stroke
				(width 0.1)
				(type default)
			)
			(layer "B.Fab")
		)
		(fp_line
			(start -0.12065 -0.2794)
			(end -0.12065 -0.3048)
			(stroke
				(width 0.1)
				(type default)
			)
			(layer "B.Fab")
		)
		(fp_line
			(start -0.12065 -0.3048)
			(end -0.67945 -0.3048)
			(stroke
				(width 0.1)
				(type default)
			)
			(layer "B.Fab")
		)
		(fp_line
			(start -0.67945 0.3048)
			(end -0.120396 0.3048)
			(stroke
				(width 0.1)
				(type default)
			)
			(layer "B.Fab")
		)
		(fp_line
			(start -0.67945 -0.3048)
			(end -0.67945 0.3048)
			(stroke
				(width 0.1)
				(type default)
			)
			(layer "B.Fab")
		)
		(pad "1" smd circle
			(at 0.40005 0)
			(size 0 0)
			(layers "B.Cu" "B.Mask" "B.Paste")
			(net "PVDDIO_P0")
		)
		(pad "2" smd circle
			(at -0.40005 0)
			(size 0 0)
			(layers "B.Cu" "B.Mask" "B.Paste")
			(net "GND")
		)
	)
	(footprint ""
		(layer "B.Cu")
		(at 239.522 -217.678 90)
		(property "Reference" "R1152"
			(at 0 0 90)
			(layer "B.SilkS")
			(hide yes)
			(effects
				(font
					(size 1.27 1.27)
				)
				(justify mirror)
			)
		)
		(property "Value" ""
			(at 0 0 90)
			(layer "B.Fab")
			(effects
				(font
					(size 1.27 1.27)
				)
				(justify mirror)
			)
		)
		(duplicate_pad_numbers_are_jumpers no)
		(fp_line
			(start 0.7874 -0.4064)
			(end -0.7874 -0.4064)
			(stroke
				(width 0.1524)
				(type default)
			)
			(layer "B.SilkS")
		)
		(fp_line
			(start -0.7874 -0.4064)
			(end -0.7874 0.4064)
			(stroke
				(width 0.1524)
				(type default)
			)
			(layer "B.SilkS")
		)
		(fp_line
			(start 0.7874 0.4064)
			(end 0.7874 -0.4064)
			(stroke
				(width 0.1524)
				(type default)
			)
			(layer "B.SilkS")
		)
		(fp_line
			(start -0.7874 0.4064)
			(end 0.7874 0.4064)
			(stroke
				(width 0.1524)
				(type default)
			)
			(layer "B.SilkS")
		)
		(fp_line
			(start 0.67945 -0.305054)
			(end 0.12065 -0.305054)
			(stroke
				(width 0.1)
				(type default)
			)
			(layer "B.Fab")
		)
		(fp_line
			(start 0.12065 -0.305054)
			(end 0.12065 -0.2794)
			(stroke
				(width 0.1)
				(type default)
			)
			(layer "B.Fab")
		)
		(fp_line
			(start -0.12065 -0.3048)
			(end -0.67945 -0.3048)
			(stroke
				(width 0.1)
				(type default)
			)
			(layer "B.Fab")
		)
		(fp_line
			(start -0.67945 -0.3048)
			(end -0.67945 0.3048)
			(stroke
				(width 0.1)
				(type default)
			)
			(layer "B.Fab")
		)
		(fp_line
			(start 0.12065 -0.2794)
			(end -0.12065 -0.2794)
			(stroke
				(width 0.1)
				(type default)
			)
			(layer "B.Fab")
		)
		(fp_line
			(start -0.12065 -0.2794)
			(end -0.12065 -0.3048)
			(stroke
				(width 0.1)
				(type default)
			)
			(layer "B.Fab")
		)
		(fp_line
			(start 0.12065 0.2794)
			(end 0.12065 0.3048)
			(stroke
				(width 0.1)
				(type default)
			)
			(layer "B.Fab")
		)
		(fp_line
			(start -0.120396 0.2794)
			(end 0.12065 0.2794)
			(stroke
				(width 0.1)
				(type default)
			)
			(layer "B.Fab")
		)
		(fp_line
			(start 0.67945 0.3048)
			(end 0.67945 -0.305054)
			(stroke
				(width 0.1)
				(type default)
			)
			(layer "B.Fab")
		)
		(fp_line
			(start 0.12065 0.3048)
			(end 0.67945 0.3048)
			(stroke
				(width 0.1)
				(type default)
			)
			(layer "B.Fab")
		)
		(fp_line
			(start -0.120396 0.3048)
			(end -0.120396 0.2794)
			(stroke
				(width 0.1)
				(type default)
			)
			(layer "B.Fab")
		)
		(fp_line
			(start -0.67945 0.3048)
			(end -0.120396 0.3048)
			(stroke
				(width 0.1)
				(type default)
			)
			(layer "B.Fab")
		)
		(pad "1" smd circle
			(at 0.40005 0 270)
			(size 0 0)
			(layers "B.Cu" "B.Mask" "B.Paste")
			(net "SMB_CPU0_CPU1_APML_BUF1_SDA_R1")
		)
		(pad "2" smd circle
			(at -0.40005 0 270)
			(size 0 0)
			(layers "B.Cu" "B.Mask" "B.Paste")
			(net "SMB_CPU0_CPU1_APML_BUF1_SDA_R2")
		)
	)
)
